# BASEBOARD_FAB2 (Tioga Pass) — schematic netlist excerpt (pin names and nets, part order shuffled) for the footprints in the layout excerpt that follows; sources: Cadence DE-HDL packaged netlist, KiCad conversion of Wiwynn_Tioga_Pass_MB.brd

C5D52  CAP_A  22.0UF 4V 20% X6S  pkg 0603V  page 42 : A = PVCCMCP_CPU0 ; B = GND
R1U1  RES  100.0K 1% CHIP  pkg 0402  page 147 : A = FAN_TACH3 ; B = GND
R2P19  RES  10.0K 1% CHIP  pkg 0402  page 135 : A = P3V3_STBY ; B = FM_DIS_ADR_DLY

(kicad_pcb
	(version 20260206)
	(generator "pcbnew")
	(generator_version "10.0")
	(general
		(thickness 1.6)
		(legacy_teardrops no)
	)
	(paper "A4")
	(title_block
		(title "Wiwynn_Tioga_Pass_MB.brd")
		(comment 1 "Tioga Pass / footprints 1416-1418 of 4770")
	)
	(layers
		(0 "F.Cu" signal "TOP")
		(4 "In1.Cu" signal "L2GND")
		(6 "In2.Cu" signal "L3")
		(8 "In3.Cu" signal "L4GND")
		(10 "In4.Cu" signal "L5")
		(12 "In5.Cu" signal "L6GND")
		(14 "In6.Cu" signal "L7VCC")
		(16 "In7.Cu" signal "L8VCC")
		(18 "In8.Cu" signal "L9GND")
		(20 "In9.Cu" signal "L10")
		(22 "In10.Cu" signal "L11GND")
		(24 "In11.Cu" signal "L12")
		(26 "In12.Cu" signal "L13GND")
		(2 "B.Cu" signal "BOTTOM")
		(9 "F.Adhes" user "F.Adhesive")
		(11 "B.Adhes" user "B.Adhesive")
		(13 "F.Paste" user "Package Geometry/Pastemask Top")
		(15 "B.Paste" user "Package Geometry/Pastemask Bottom")
		(5 "F.SilkS" user "Ref Des/Silkscreen Top")
		(7 "B.SilkS" user "Ref Des/Silkscreen Bottom")
		(1 "F.Mask" user "Board Geometry/Soldermask Top")
		(3 "B.Mask" user "Board Geometry/Soldermask Bottom")
		(17 "Dwgs.User" user "User.Drawings")
		(19 "Cmts.User" user "User.Comments")
		(21 "Eco1.User" user "User.Eco1")
		(23 "Eco2.User" user "User.Eco2")
		(25 "Edge.Cuts" user "Board Geometry/Outline")
		(27 "Margin" user)
		(31 "F.CrtYd" user "Package Geometry/Place Bound Top")
		(29 "B.CrtYd" user "Package Geometry/Place Bound Bottom")
		(35 "F.Fab" user "Ref Des/Assembly Top")
		(33 "B.Fab" user "Ref Des/Assembly Bottom")
	)
	(footprint ""
		(layer "F.Cu")
		(at 270.628872 -73.279)
		(property "Reference" "C5D52"
			(at 0 0 0)
			(layer "F.SilkS")
			(hide yes)
			(effects
				(font
					(size 1.27 1.27)
				)
			)
		)
		(property "Value" ""
			(at 0 0 0)
			(layer "F.Fab")
			(effects
				(font
					(size 1.27 1.27)
				)
			)
		)
		(duplicate_pad_numbers_are_jumpers no)
		(fp_poly
			(pts
				(xy -0.4953 -0.2032) (xy 0.4953 -0.2032) (xy 0.4953 1.6002) (xy -0.4953 1.6002)
			)
			(stroke
				(width 0)
				(type default)
			)
			(fill no)
			(layer "F.CrtYd")
		)
		(fp_line
			(start -0.4953 -0.2032)
			(end 0.4953 -0.2032)
			(stroke
				(width 0.1)
				(type default)
			)
			(layer "F.Fab")
		)
		(fp_line
			(start -0.4953 1.6002)
			(end -0.4953 -0.2032)
			(stroke
				(width 0.1)
				(type default)
			)
			(layer "F.Fab")
		)
		(fp_line
			(start 0.4953 -0.2032)
			(end 0.4953 1.6002)
			(stroke
				(width 0.1)
				(type default)
			)
			(layer "F.Fab")
		)
		(fp_line
			(start 0.4953 1.6002)
			(end -0.4953 1.6002)
			(stroke
				(width 0.1)
				(type default)
			)
			(layer "F.Fab")
		)
		(pad "1" smd rect
			(at 0 0)
			(size 0.762 0.889)
			(layers "F.Cu" "F.Mask" "F.Paste")
			(net "PVCCMCP_CPU0")
		)
		(pad "2" smd rect
			(at 0 1.397)
			(size 0.762 0.889)
			(layers "F.Cu" "F.Mask" "F.Paste")
			(net "GND")
		)
		(zone
			(layer "F.Cu")
			(hatch none 0.5)
			(connect_pads
				(clearance 0)
			)
			(min_thickness 0.25)
			(keepout
				(tracks not_allowed)
				(vias allowed)
				(pads allowed)
				(copperpour not_allowed)
				(footprints allowed)
			)
			(placement
				(enabled no)
				(sheetname "")
			)
			(fill
				(thermal_gap 0.5)
				(thermal_bridge_width 0.5)
				(island_removal_mode 0)
			)
			(polygon
				(pts
					(xy 270.247872 -72.8345) (xy 271.009872 -72.8345) (xy 271.009872 -72.3265) (xy 270.247872 -72.3265)
				)
			)
		)
	)
	(footprint ""
		(layer "F.Cu")
		(at 444.1825 -1.143 -90)
		(property "Reference" "R2P19"
			(at 0 0 270)
			(layer "F.SilkS")
			(hide yes)
			(effects
				(font
					(size 1.27 1.27)
				)
			)
		)
		(property "Value" ""
			(at 0 0 270)
			(layer "F.Fab")
			(effects
				(font
					(size 1.27 1.27)
				)
			)
		)
		(duplicate_pad_numbers_are_jumpers no)
		(fp_poly
			(pts
				(xy -0.2794 -0.1016) (xy 0.2794 -0.1016) (xy 0.2794 0.9906) (xy -0.2794 0.9906)
			)
			(stroke
				(width 0)
				(type default)
			)
			(fill no)
			(layer "F.CrtYd")
		)
		(fp_line
			(start -0.2794 0.9906)
			(end 0.2794 0.9906)
			(stroke
				(width 0.1)
				(type default)
			)
			(layer "F.Fab")
		)
		(fp_line
			(start 0.2794 0.9906)
			(end 0.2794 -0.1016)
			(stroke
				(width 0.1)
				(type default)
			)
			(layer "F.Fab")
		)
		(fp_line
			(start -0.2794 -0.1016)
			(end -0.2794 0.9906)
			(stroke
				(width 0.1)
				(type default)
			)
			(layer "F.Fab")
		)
		(fp_line
			(start 0.2794 -0.1016)
			(end -0.2794 -0.1016)
			(stroke
				(width 0.1)
				(type default)
			)
			(layer "F.Fab")
		)
		(pad "1" smd rect
			(at 0 0 270)
			(size 0.508 0.508)
			(layers "F.Cu" "F.Mask" "F.Paste")
			(net "P3V3_STBY")
		)
		(pad "2" smd rect
			(at 0 0.889 270)
			(size 0.508 0.508)
			(layers "F.Cu" "F.Mask" "F.Paste")
			(net "FM_DIS_ADR_DLY")
		)
		(zone
			(layer "F.Cu")
			(hatch none 0.5)
			(connect_pads
				(clearance 0)
			)
			(min_thickness 0.25)
			(keepout
				(tracks not_allowed)
				(vias allowed)
				(pads allowed)
				(copperpour not_allowed)
				(footprints allowed)
			)
			(placement
				(enabled no)
				(sheetname "")
			)
			(fill
				(thermal_gap 0.5)
				(thermal_bridge_width 0.5)
				(island_removal_mode 0)
			)
			(polygon
				(pts
					(xy 443.5475 -1.397) (xy 443.5475 -0.889) (xy 443.9285 -0.889) (xy 443.9285 -1.397)
				)
			)
		)
		(zone
			(layer "F.Cu")
			(hatch none 0.5)
			(connect_pads
				(clearance 0)
			)
			(min_thickness 0.25)
			(keepout
				(tracks allowed)
				(vias not_allowed)
				(pads allowed)
				(copperpour not_allowed)
				(footprints allowed)
			)
			(placement
				(enabled no)
				(sheetname "")
			)
			(fill
				(thermal_gap 0.5)
				(thermal_bridge_width 0.5)
				(island_removal_mode 0)
			)
			(polygon
				(pts
					(xy 443.9285 -1.397) (xy 443.9285 -0.889) (xy 443.5475 -0.889) (xy 443.5475 -1.397)
				)
			)
		)
	)
	(footprint ""
		(layer "F.Cu")
		(at 437.6293 -21.9964 -90)
		(property "Reference" "R1U1"
			(at 0 0 270)
			(layer "F.SilkS")
			(hide yes)
			(effects
				(font
					(size 1.27 1.27)
				)
			)
		)
		(property "Value" ""
			(at 0 0 270)
			(layer "F.Fab")
			(effects
				(font
					(size 1.27 1.27)
				)
			)
		)
		(duplicate_pad_numbers_are_jumpers no)
		(fp_poly
			(pts
				(xy -0.2794 -0.1016) (xy 0.2794 -0.1016) (xy 0.2794 0.9906) (xy -0.2794 0.9906)
			)
			(stroke
				(width 0)
				(type default)
			)
			(fill no)
			(layer "F.CrtYd")
		)
		(fp_line
			(start -0.2794 0.9906)
			(end 0.2794 0.9906)
			(stroke
				(width 0.1)
				(type default)
			)
			(layer "F.Fab")
		)
		(fp_line
			(start 0.2794 0.9906)
			(end 0.2794 -0.1016)
			(stroke
				(width 0.1)
				(type default)
			)
			(layer "F.Fab")
		)
		(fp_line
			(start -0.2794 -0.1016)
			(end -0.2794 0.9906)
			(stroke
				(width 0.1)
				(type default)
			)
			(layer "F.Fab")
		)
		(fp_line
			(start 0.2794 -0.1016)
			(end -0.2794 -0.1016)
			(stroke
				(width 0.1)
				(type default)
			)
			(layer "F.Fab")
		)
		(pad "1" smd rect
			(at 0 0 270)
			(size 0.508 0.508)
			(layers "F.Cu" "F.Mask" "F.Paste")
			(net "FAN_TACH3")
		)
		(pad "2" smd rect
			(at 0 0.889 270)
			(size 0.508 0.508)
			(layers "F.Cu" "F.Mask" "F.Paste")
			(net "GND")
		)
		(zone
			(layer "F.Cu")
			(hatch none 0.5)
			(connect_pads
				(clearance 0)
			)
			(min_thickness 0.25)
			(keepout
				(tracks not_allowed)
				(vias allowed)
				(pads allowed)
				(copperpour not_allowed)
				(footprints allowed)
			)
			(placement
				(enabled no)
				(sheetname "")
			)
			(fill
				(thermal_gap 0.5)
				(thermal_bridge_width 0.5)
				(island_removal_mode 0)
			)
			(polygon
				(pts
					(xy 436.9943 -22.2504) (xy 436.9943 -21.7424) (xy 437.3753 -21.7424) (xy 437.3753 -22.2504)
				)
			)
		)
		(zone
			(layer "F.Cu")
			(hatch none 0.5)
			(connect_pads
				(clearance 0)
			)
			(min_thickness 0.25)
			(keepout
				(tracks allowed)
				(vias not_allowed)
				(pads allowed)
				(copperpour not_allowed)
				(footprints allowed)
			)
			(placement
				(enabled no)
				(sheetname "")
			)
			(fill
				(thermal_gap 0.5)
				(thermal_bridge_width 0.5)
				(island_removal_mode 0)
			)
			(polygon
				(pts
					(xy 437.3753 -22.2504) (xy 437.3753 -21.7424) (xy 436.9943 -21.7424) (xy 436.9943 -22.2504)
				)
			)
		)
	)
)
